# SCM (Grand Teton) — schematic netlist excerpt (pin names and nets, part order shuffled) for the footprints in the layout excerpt that follows; sources: Cadence DE-HDL packaged netlist, KiCad conversion of 12092022_DA0F0TMDCD0_F0T_Management_Board_D_brd_V3_OCP.brd

C4  Q_CAP  1UF 25V 10% X6S  pkg C0402  page 20 : A = P1V2_AUX ; B = GND
C10  Q_CAP  0.1UF 25V 10% X7R  pkg 0402  page 20 : A = P0V6_DDR_VREF_AUX ; B = GND

(kicad_pcb
	(version 20260206)
	(generator "pcbnew")
	(generator_version "10.0")
	(general
		(thickness 1.6)
		(legacy_teardrops no)
	)
	(paper "A4")
	(title_block
		(title "12092022_DA0F0TMDCD0_F0T_Management_Board_D_brd_V3_OCP.brd")
		(comment 1 "Grand Teton / footprints 887-888 of 1440")
	)
	(layers
		(0 "F.Cu" signal "TOP")
		(4 "In1.Cu" signal "GND")
		(6 "In2.Cu" signal "IN1")
		(8 "In3.Cu" signal "GND1")
		(10 "In4.Cu" signal "IN2")
		(12 "In5.Cu" signal "VCC")
		(14 "In6.Cu" signal "VCC1")
		(16 "In7.Cu" signal "IN3")
		(18 "In8.Cu" signal "GND2")
		(20 "In9.Cu" signal "IN4")
		(22 "In10.Cu" signal "GND3")
		(2 "B.Cu" signal "BOTTOM")
		(9 "F.Adhes" user "F.Adhesive")
		(11 "B.Adhes" user "B.Adhesive")
		(13 "F.Paste" user "Package Geometry/Pastemask Top")
		(15 "B.Paste" user "Package Geometry/Pastemask Bottom")
		(5 "F.SilkS" user "Ref Des/Silkscreen Top")
		(7 "B.SilkS" user "Ref Des/Silkscreen Bottom")
		(1 "F.Mask" user "Board Geometry/Soldermask Top")
		(3 "B.Mask" user "Board Geometry/Soldermask Bottom")
		(17 "Dwgs.User" user "User.Drawings")
		(19 "Cmts.User" user "User.Comments")
		(21 "Eco1.User" user "User.Eco1")
		(23 "Eco2.User" user "User.Eco2")
		(25 "Edge.Cuts" user "Board Geometry/Outline")
		(27 "Margin" user)
		(31 "F.CrtYd" user "Package Geometry/Place Bound Top")
		(29 "B.CrtYd" user "Package Geometry/Place Bound Bottom")
		(35 "F.Fab" user "Ref Des/Assembly Top")
		(33 "B.Fab" user "Ref Des/Assembly Bottom")
	)
	(footprint ""
		(layer "B.Cu")
		(at 76.162154 -52.286916 180)
		(property "Reference" "C4"
			(at 0 0 0)
			(layer "B.SilkS")
			(hide yes)
			(effects
				(font
					(size 1.27 1.27)
				)
				(justify mirror)
			)
		)
		(property "Value" ""
			(at 0 0 0)
			(layer "B.Fab")
			(effects
				(font
					(size 1.27 1.27)
				)
				(justify mirror)
			)
		)
		(duplicate_pad_numbers_are_jumpers no)
		(fp_line
			(start 0.7874 0.4064)
			(end 0.7874 -0.4064)
			(stroke
				(width 0.1524)
				(type default)
			)
			(layer "B.SilkS")
		)
		(fp_line
			(start 0.7874 -0.4064)
			(end -0.7874 -0.4064)
			(stroke
				(width 0.1524)
				(type default)
			)
			(layer "B.SilkS")
		)
		(fp_line
			(start -0.7874 0.4064)
			(end 0.7874 0.4064)
			(stroke
				(width 0.1524)
				(type default)
			)
			(layer "B.SilkS")
		)
		(fp_line
			(start -0.7874 -0.4064)
			(end -0.7874 0.4064)
			(stroke
				(width 0.1524)
				(type default)
			)
			(layer "B.SilkS")
		)
		(fp_line
			(start 0.67945 0.3048)
			(end 0.67945 -0.305054)
			(stroke
				(width 0.1)
				(type default)
			)
			(layer "B.Fab")
		)
		(fp_line
			(start 0.67945 -0.305054)
			(end 0.12065 -0.305054)
			(stroke
				(width 0.1)
				(type default)
			)
			(layer "B.Fab")
		)
		(fp_line
			(start 0.12065 0.3048)
			(end 0.67945 0.3048)
			(stroke
				(width 0.1)
				(type default)
			)
			(layer "B.Fab")
		)
		(fp_line
			(start 0.12065 0.2794)
			(end 0.12065 0.3048)
			(stroke
				(width 0.1)
				(type default)
			)
			(layer "B.Fab")
		)
		(fp_line
			(start 0.12065 -0.2794)
			(end -0.12065 -0.2794)
			(stroke
				(width 0.1)
				(type default)
			)
			(layer "B.Fab")
		)
		(fp_line
			(start 0.12065 -0.305054)
			(end 0.12065 -0.2794)
			(stroke
				(width 0.1)
				(type default)
			)
			(layer "B.Fab")
		)
		(fp_line
			(start -0.120396 0.3048)
			(end -0.120396 0.2794)
			(stroke
				(width 0.1)
				(type default)
			)
			(layer "B.Fab")
		)
		(fp_line
			(start -0.120396 0.2794)
			(end 0.12065 0.2794)
			(stroke
				(width 0.1)
				(type default)
			)
			(layer "B.Fab")
		)
		(fp_line
			(start -0.12065 -0.2794)
			(end -0.12065 -0.3048)
			(stroke
				(width 0.1)
				(type default)
			)
			(layer "B.Fab")
		)
		(fp_line
			(start -0.12065 -0.3048)
			(end -0.67945 -0.3048)
			(stroke
				(width 0.1)
				(type default)
			)
			(layer "B.Fab")
		)
		(fp_line
			(start -0.67945 0.3048)
			(end -0.120396 0.3048)
			(stroke
				(width 0.1)
				(type default)
			)
			(layer "B.Fab")
		)
		(fp_line
			(start -0.67945 -0.3048)
			(end -0.67945 0.3048)
			(stroke
				(width 0.1)
				(type default)
			)
			(layer "B.Fab")
		)
		(pad "1" smd circle
			(at 0.40005 0)
			(size 0 0)
			(layers "B.Cu" "B.Mask" "B.Paste")
			(net "P1V2_AUX")
		)
		(pad "2" smd circle
			(at -0.40005 0)
			(size 0 0)
			(layers "B.Cu" "B.Mask" "B.Paste")
			(net "GND")
		)
	)
	(footprint ""
		(layer "B.Cu")
		(at 71.66102 -44.61129)
		(property "Reference" "C10"
			(at 0 0 0)
			(layer "B.SilkS")
			(hide yes)
			(effects
				(font
					(size 1.27 1.27)
				)
				(justify mirror)
			)
		)
		(property "Value" ""
			(at 0 0 0)
			(layer "B.Fab")
			(effects
				(font
					(size 1.27 1.27)
				)
				(justify mirror)
			)
		)
		(duplicate_pad_numbers_are_jumpers no)
		(fp_line
			(start -0.7874 -0.4064)
			(end -0.7874 0.4064)
			(stroke
				(width 0.1524)
				(type default)
			)
			(layer "B.SilkS")
		)
		(fp_line
			(start -0.7874 0.4064)
			(end 0.7874 0.4064)
			(stroke
				(width 0.1524)
				(type default)
			)
			(layer "B.SilkS")
		)
		(fp_line
			(start 0.7874 -0.4064)
			(end -0.7874 -0.4064)
			(stroke
				(width 0.1524)
				(type default)
			)
			(layer "B.SilkS")
		)
		(fp_line
			(start 0.7874 0.4064)
			(end 0.7874 -0.4064)
			(stroke
				(width 0.1524)
				(type default)
			)
			(layer "B.SilkS")
		)
		(fp_line
			(start -0.67945 -0.3048)
			(end -0.67945 0.3048)
			(stroke
				(width 0.1)
				(type default)
			)
			(layer "B.Fab")
		)
		(fp_line
			(start -0.67945 0.3048)
			(end -0.120396 0.3048)
			(stroke
				(width 0.1)
				(type default)
			)
			(layer "B.Fab")
		)
		(fp_line
			(start -0.12065 -0.3048)
			(end -0.67945 -0.3048)
			(stroke
				(width 0.1)
				(type default)
			)
			(layer "B.Fab")
		)
		(fp_line
			(start -0.12065 -0.2794)
			(end -0.12065 -0.3048)
			(stroke
				(width 0.1)
				(type default)
			)
			(layer "B.Fab")
		)
		(fp_line
			(start -0.120396 0.2794)
			(end 0.12065 0.2794)
			(stroke
				(width 0.1)
				(type default)
			)
			(layer "B.Fab")
		)
		(fp_line
			(start -0.120396 0.3048)
			(end -0.120396 0.2794)
			(stroke
				(width 0.1)
				(type default)
			)
			(layer "B.Fab")
		)
		(fp_line
			(start 0.12065 -0.305054)
			(end 0.12065 -0.2794)
			(stroke
				(width 0.1)
				(type default)
			)
			(layer "B.Fab")
		)
		(fp_line
			(start 0.12065 -0.2794)
			(end -0.12065 -0.2794)
			(stroke
				(width 0.1)
				(type default)
			)
			(layer "B.Fab")
		)
		(fp_line
			(start 0.12065 0.2794)
			(end 0.12065 0.3048)
			(stroke
				(width 0.1)
				(type default)
			)
			(layer "B.Fab")
		)
		(fp_line
			(start 0.12065 0.3048)
			(end 0.67945 0.3048)
			(stroke
				(width 0.1)
				(type default)
			)
			(layer "B.Fab")
		)
		(fp_line
			(start 0.67945 -0.305054)
			(end 0.12065 -0.305054)
			(stroke
				(width 0.1)
				(type default)
			)
			(layer "B.Fab")
		)
		(fp_line
			(start 0.67945 0.3048)
			(end 0.67945 -0.305054)
			(stroke
				(width 0.1)
				(type default)
			)
			(layer "B.Fab")
		)
		(pad "1" smd circle
			(at 0.40005 0 180)
			(size 0 0)
			(layers "B.Cu" "B.Mask" "B.Paste")
			(net "P0V6_DDR_VREF_AUX")
		)
		(pad "2" smd circle
			(at -0.40005 0 180)
			(size 0 0)
			(layers "B.Cu" "B.Mask" "B.Paste")
			(net "GND")
		)
	)
)
